(kicad_pcb
	(version 20260206)
	(generator "pcbnew")
	(generator_version "10.0")
	(general
		(thickness 1.6)
		(legacy_teardrops no)
	)
	(paper "A4")
	(title_block
		(title "Bryce Canyon_IOM_IOC_16318-2_OCP.brd")
		(comment 1 "Bryce Canyon / footprints 259-260 of 1605")
	)
	(layers
		(0 "F.Cu" signal "TOP")
		(4 "In1.Cu" signal "L2GND")
		(6 "In2.Cu" signal "L3")
		(8 "In3.Cu" signal "L4VCC")
		(10 "In4.Cu" signal "L5VCC")
		(12 "In5.Cu" signal "L6")
		(14 "In6.Cu" signal "L7GND")
		(2 "B.Cu" signal "BOTTOM")
		(9 "F.Adhes" user "F.Adhesive")
		(11 "B.Adhes" user "B.Adhesive")
		(13 "F.Paste" user "Package Geometry/Pastemask Top")
		(15 "B.Paste" user "Package Geometry/Pastemask Bottom")
		(5 "F.SilkS" user "Ref Des/Silkscreen Top")
		(7 "B.SilkS" user "Ref Des/Silkscreen Bottom")
		(1 "F.Mask" user "Board Geometry/Soldermask Top")
		(3 "B.Mask" user "Board Geometry/Soldermask Bottom")
		(17 "Dwgs.User" user "User.Drawings")
		(19 "Cmts.User" user "User.Comments")
		(21 "Eco1.User" user "User.Eco1")
		(23 "Eco2.User" user "User.Eco2")
		(25 "Edge.Cuts" user "Board Geometry/Outline")
		(27 "Margin" user)
		(31 "F.CrtYd" user "Package Geometry/Place Bound Top")
		(29 "B.CrtYd" user "Package Geometry/Place Bound Bottom")
		(35 "F.Fab" user "Ref Des/Assembly Top")
		(33 "B.Fab" user "Ref Des/Assembly Bottom")
	)
	(footprint ""
		(layer "F.Cu")
		(at 75.091036 -180.35778 -90)
		(property "Reference" "PU9"
			(at 0 0 270)
			(layer "F.SilkS")
			(hide yes)
			(effects
				(font
					(size 1.27 1.27)
				)
			)
		)
		(property "Value" "TPS74801RGW-GP"
			(at -4.7244 -6.223 270)
			(unlocked yes)
			(layer "F.Fab")
			(hide yes)
			(effects
				(font
					(size 1.016 1.016)
					(thickness 0.1524)
				)
			)
		)
		(property "Device Type" "QFN20-1G3D15H40"
			(at -4.7244 -7.747 270)
			(unlocked yes)
			(layer "F.Fab")
			(hide yes)
			(effects
				(font
					(size 1.016 1.016)
					(thickness 0.1524)
				)
			)
		)
		(duplicate_pad_numbers_are_jumpers no)
		(fp_line
			(start -3.5179 3.5179)
			(end -2.2479 3.5179)
			(stroke
				(width 0.1524)
				(type default)
			)
			(layer "F.SilkS")
		)
		(fp_line
			(start 2.2479 3.5179)
			(end 3.5179 3.5179)
			(stroke
				(width 0.1524)
				(type default)
			)
			(layer "F.SilkS")
		)
		(fp_line
			(start 3.5179 3.5179)
			(end 3.5179 2.2479)
			(stroke
				(width 0.1524)
				(type default)
			)
			(layer "F.SilkS")
		)
		(fp_line
			(start 1.299972 3.160522)
			(end 1.299972 3.668522)
			(stroke
				(width 0.1524)
				(type default)
			)
			(layer "F.SilkS")
		)
		(fp_line
			(start -3.5179 2.2479)
			(end -3.5179 3.5179)
			(stroke
				(width 0.1524)
				(type default)
			)
			(layer "F.SilkS")
		)
		(fp_line
			(start -3.160522 1.299972)
			(end -3.922522 1.299972)
			(stroke
				(width 0.1524)
				(type default)
			)
			(layer "F.SilkS")
		)
		(fp_line
			(start 3.160522 -1.299972)
			(end 3.922522 -1.299972)
			(stroke
				(width 0.1524)
				(type default)
			)
			(layer "F.SilkS")
		)
		(fp_line
			(start -1.299972 -3.160522)
			(end -1.299972 -3.668522)
			(stroke
				(width 0.1524)
				(type default)
			)
			(layer "F.SilkS")
		)
		(fp_line
			(start -3.5179 -3.5179)
			(end -3.5179 -2.2479)
			(stroke
				(width 0.1524)
				(type default)
			)
			(layer "F.SilkS")
		)
		(fp_line
			(start -2.2479 -3.5179)
			(end -3.5179 -3.5179)
			(stroke
				(width 0.1524)
				(type default)
			)
			(layer "F.SilkS")
		)
		(fp_poly
			(pts
				(xy 3.5179 -3.5179) (xy 2.2479 -3.5179) (xy 3.5179 -2.2479)
			)
			(stroke
				(width 0)
				(type default)
			)
			(fill yes)
			(layer "F.SilkS")
		)
		(fp_rect
			(start -2.5019 2.5019)
			(end 2.5019 -2.5019)
			(stroke
				(width 0)
				(type default)
			)
			(fill no)
			(layer "F.CrtYd")
		)
		(fp_poly
			(pts
				(xy -3.5179 3.5179) (xy -3.5179 -3.5179) (xy 3.5179 -3.5179) (xy 3.5179 -2.5019) (xy -2.5019 -2.5019)
				(xy -2.5019 2.5019) (xy 2.5019 2.5019) (xy 2.5019 -2.49682) (xy 3.5179 -2.49682) (xy 3.5179 3.5179)
			)
			(stroke
				(width 0)
				(type default)
			)
			(fill no)
			(layer "F.CrtYd")
		)
		(fp_rect
			(start -3.5179 3.5179)
			(end 3.5179 -3.5179)
			(stroke
				(width 0)
				(type default)
			)
			(fill no)
			(layer "F.Fab")
		)
		(pad "1" smd rect
			(at 1.299972 -2.474722 270)
			(size 0.3556 1.0668)
			(layers "F.Cu" "F.Mask" "F.Paste")
			(net "TPS74801_P2V5_STBY_OUT")
		)
		(pad "2" smd rect
			(at 0.649986 -2.474722 270)
			(size 0.3556 1.0668)
			(layers "F.Cu" "F.Mask" "F.Paste")
			(net "GND")
		)
		(pad "3" smd rect
			(at 0 -2.474722 270)
			(size 0.3556 1.0668)
			(layers "F.Cu" "F.Mask" "F.Paste")
			(net "GND")
		)
		(pad "4" smd rect
			(at -0.649986 -2.474722 270)
			(size 0.3556 1.0668)
			(layers "F.Cu" "F.Mask" "F.Paste")
			(net "GND")
		)
		(pad "5" smd rect
			(at -1.299972 -2.474722 270)
			(size 0.3556 1.0668)
			(layers "F.Cu" "F.Mask" "F.Paste")
			(net "P3V3_STBY")
		)
		(pad "6" smd rect
			(at -2.474722 -1.299972 270)
			(size 1.0668 0.3556)
			(layers "F.Cu" "F.Mask" "F.Paste")
			(net "P3V3_STBY")
		)
		(pad "7" smd rect
			(at -2.474722 -0.649986 270)
			(size 1.0668 0.3556)
			(layers "F.Cu" "F.Mask" "F.Paste")
			(net "P3V3_STBY")
		)
		(pad "8" smd rect
			(at -2.474722 0 270)
			(size 1.0668 0.3556)
			(layers "F.Cu" "F.Mask" "F.Paste")
			(net "P3V3_STBY")
		)
		(pad "9" smd rect
			(at -2.474722 0.649986 270)
			(size 1.0668 0.3556)
			(layers "F.Cu" "F.Mask" "F.Paste")
			(net "PWRGD_P2V5_STBY")
		)
		(pad "10" smd rect
			(at -2.474722 1.299972 270)
			(size 1.0668 0.3556)
			(layers "F.Cu" "F.Mask" "F.Paste")
			(net "TPS74801_P2V5_STBY_BIAS")
		)
		(pad "11" smd rect
			(at -1.299972 2.474722 270)
			(size 0.3556 1.0668)
			(layers "F.Cu" "F.Mask" "F.Paste")
			(net "TPS74801_P2V5_STBY_EN")
		)
		(pad "12" smd rect
			(at -0.649986 2.474722 270)
			(size 0.3556 1.0668)
			(layers "F.Cu" "F.Mask" "F.Paste")
			(net "GND")
		)
		(pad "13" smd rect
			(at 0 2.474722 270)
			(size 0.3556 1.0668)
			(layers "F.Cu" "F.Mask" "F.Paste")
			(net "GND")
		)
		(pad "14" smd rect
			(at 0.649986 2.474722 270)
			(size 0.3556 1.0668)
			(layers "F.Cu" "F.Mask" "F.Paste")
			(net "GND")
		)
		(pad "15" smd rect
			(at 1.299972 2.474722 270)
			(size 0.3556 1.0668)
			(layers "F.Cu" "F.Mask" "F.Paste")
			(net "TPS74801_P2V5_STBY_SS")
		)
		(pad "16" smd rect
			(at 2.474722 1.299972 270)
			(size 1.0668 0.3556)
			(layers "F.Cu" "F.Mask" "F.Paste")
			(net "TPS74801_P2V5_STBY_FB")
		)
		(pad "17" smd rect
			(at 2.474722 0.649986 270)
			(size 1.0668 0.3556)
			(layers "F.Cu" "F.Mask" "F.Paste")
			(net "GND")
		)
		(pad "18" smd rect
			(at 2.474722 0 270)
			(size 1.0668 0.3556)
			(layers "F.Cu" "F.Mask" "F.Paste")
			(net "TPS74801_P2V5_STBY_OUT")
		)
		(pad "19" smd rect
			(at 2.474722 -0.649986 270)
			(size 1.0668 0.3556)
			(layers "F.Cu" "F.Mask" "F.Paste")
			(net "TPS74801_P2V5_STBY_OUT")
		)
		(pad "20" smd rect
			(at 2.474722 -1.299972 270)
			(size 1.0668 0.3556)
			(layers "F.Cu" "F.Mask" "F.Paste")
			(net "TPS74801_P2V5_STBY_OUT")
		)
		(pad "21" smd rect
			(at 0 0 270)
			(size 3.2512 3.2512)
			(layers "F.Cu" "F.Mask" "F.Paste")
			(net "GND")
		)
	)
	(footprint ""
		(layer "F.Cu")
		(at 66.675 -137.033 90)
		(property "Reference" "R49"
			(at 0 0 90)
			(layer "F.SilkS")
			(hide yes)
			(effects
				(font
					(size 1.27 1.27)
				)
			)
		)
		(property "Value" "10KR2F-2-GP"
			(at 0.064008 -3.993896 90)
			(unlocked yes)
			(layer "F.Fab")
			(hide yes)
			(effects
				(font
					(size 1.016 1.016)
					(thickness 0.1524)
				)
			)
		)
		(property "Device Type" "R402H16"
			(at 0.064008 -5.517896 90)
			(unlocked yes)
			(layer "F.Fab")
			(hide yes)
			(effects
				(font
					(size 1.016 1.016)
					(thickness 0.1524)
				)
			)
		)
		(duplicate_pad_numbers_are_jumpers no)
		(fp_line
			(start 0.508 -0.9398)
			(end -0.508 -0.9398)
			(stroke
				(width 0.1524)
				(type default)
			)
			(layer "F.SilkS")
		)
		(fp_line
			(start -0.508 -0.9398)
			(end -0.508 0.9398)
			(stroke
				(width 0.1524)
				(type default)
			)
			(layer "F.SilkS")
		)
		(fp_rect
			(start -0.508 0.9398)
			(end 0.508 -0.9398)
			(stroke
				(width 0)
				(type default)
			)
			(fill no)
			(layer "F.CrtYd")
		)
		(fp_rect
			(start -0.508 0.9398)
			(end 0.508 -0.9398)
			(stroke
				(width 0)
				(type default)
			)
			(fill no)
			(layer "F.Fab")
		)
		(pad "1" smd custom
			(at 0 -0.4445 90)
			(size 0.1397 0.1397)
			(layers "F.Cu" "F.Mask" "F.Paste")
			(net "P3V3_STBY")
			(options
				(clearance outline)
				(anchor circle)
			)
			(primitives
				(gr_poly
					(pts
						(arc
							(start -0.1778 -0.2794)
							(mid -0.249642 -0.249642)
							(end -0.2794 -0.1778)
						)
						(arc
							(start -0.2794 0.1778)
							(mid -0.249642 0.249642)
							(end -0.1778 0.2794)
						)
						(arc
							(start 0.1778 0.2794)
							(mid 0.249642 0.249642)
							(end 0.2794 0.1778)
						)
						(arc
							(start 0.2794 -0.1778)
							(mid 0.249642 -0.249642)
							(end 0.1778 -0.2794)
						)
					)
					(width 0)
					(fill yes)
				)
			)
		)
		(pad "2" smd custom
			(at 0 0.4445 90)
			(size 0.1397 0.1397)
			(layers "F.Cu" "F.Mask" "F.Paste")
			(net "FP_PWRBTN")
			(options
				(clearance outline)
				(anchor circle)
			)
			(primitives
				(gr_poly
					(pts
						(arc
							(start -0.1778 -0.2794)
							(mid -0.249642 -0.249642)
							(end -0.2794 -0.1778)
						)
						(arc
							(start -0.2794 0.1778)
							(mid -0.249642 0.249642)
							(end -0.1778 0.2794)
						)
						(arc
							(start 0.1778 0.2794)
							(mid 0.249642 0.249642)
							(end 0.2794 0.1778)
						)
						(arc
							(start 0.2794 -0.1778)
							(mid 0.249642 -0.249642)
							(end 0.1778 -0.2794)
						)
					)
					(width 0)
					(fill yes)
				)
			)
		)
	)
)
